# T6G (Grand Teton) — schematic netlist excerpt (pin names and nets, part order shuffled) for the footprints in the layout excerpt that follows; sources: Cadence DE-HDL packaged netlist, KiCad conversion of 04192023_DAF0TMB3IC0_F0TG_MB_C_brd_V02_OCP.brd

C1998  Q_CAP  0.1UF 25V 10% X7R  pkg 0402  page 148 : A = P3V3_E1S_0 ; B = GND
PC85_1  Q_CAP  0.1UF 25V 10% X7R  pkg 0402  page 201 : A = SW_P12V_AUX_PVDDCR_CPU1_P0_FLT ; B = GND

(kicad_pcb
	(version 20260206)
	(generator "pcbnew")
	(generator_version "10.0")
	(general
		(thickness 1.6)
		(legacy_teardrops no)
	)
	(paper "A4")
	(title_block
		(title "04192023_DAF0TMB3IC0_F0TG_MB_C_brd_V02_OCP.brd")
		(comment 1 "Grand Teton / footprints 3293-3294 of 8354")
	)
	(layers
		(0 "F.Cu" signal "TOP")
		(4 "In1.Cu" signal "GND")
		(6 "In2.Cu" signal "IN1")
		(8 "In3.Cu" signal "GND1")
		(10 "In4.Cu" signal "IN2")
		(12 "In5.Cu" signal "GND2")
		(14 "In6.Cu" signal "IN3")
		(16 "In7.Cu" signal "GND3")
		(18 "In8.Cu" signal "VCC")
		(20 "In9.Cu" signal "VCC1")
		(22 "In10.Cu" signal "GND4")
		(24 "In11.Cu" signal "IN4")
		(26 "In12.Cu" signal "GND5")
		(28 "In13.Cu" signal "IN5")
		(30 "In14.Cu" signal "GND6")
		(32 "In15.Cu" signal "IN6")
		(34 "In16.Cu" signal "GND7")
		(2 "B.Cu" signal "BOTTOM")
		(9 "F.Adhes" user "F.Adhesive")
		(11 "B.Adhes" user "B.Adhesive")
		(13 "F.Paste" user "Package Geometry/Pastemask Top")
		(15 "B.Paste" user "Package Geometry/Pastemask Bottom")
		(5 "F.SilkS" user "Ref Des/Silkscreen Top")
		(7 "B.SilkS" user "Ref Des/Silkscreen Bottom")
		(1 "F.Mask" user "Board Geometry/Soldermask Top")
		(3 "B.Mask" user "Board Geometry/Soldermask Bottom")
		(17 "Dwgs.User" user "User.Drawings")
		(19 "Cmts.User" user "User.Comments")
		(21 "Eco1.User" user "User.Eco1")
		(23 "Eco2.User" user "User.Eco2")
		(25 "Edge.Cuts" user "Board Geometry/Outline")
		(27 "Margin" user)
		(31 "F.CrtYd" user "Package Geometry/Place Bound Top")
		(29 "B.CrtYd" user "Package Geometry/Place Bound Bottom")
		(35 "F.Fab" user "Ref Des/Assembly Top")
		(33 "B.Fab" user "Ref Des/Assembly Bottom")
	)
	(footprint ""
		(layer "F.Cu")
		(at 330.922884 -339.35797)
		(property "Reference" "PC85_1"
			(at 0 0 0)
			(layer "F.SilkS")
			(hide yes)
			(effects
				(font
					(size 1.27 1.27)
				)
			)
		)
		(property "Value" ""
			(at 0 0 0)
			(layer "F.Fab")
			(effects
				(font
					(size 1.27 1.27)
				)
			)
		)
		(duplicate_pad_numbers_are_jumpers no)
		(fp_line
			(start -0.7874 -0.4064)
			(end 0.7874 -0.4064)
			(stroke
				(width 0.1524)
				(type default)
			)
			(layer "F.SilkS")
		)
		(fp_line
			(start -0.7874 0.4064)
			(end -0.7874 -0.4064)
			(stroke
				(width 0.1524)
				(type default)
			)
			(layer "F.SilkS")
		)
		(fp_line
			(start 0.7874 -0.4064)
			(end 0.7874 0.4064)
			(stroke
				(width 0.1524)
				(type default)
			)
			(layer "F.SilkS")
		)
		(fp_line
			(start 0.7874 0.4064)
			(end -0.7874 0.4064)
			(stroke
				(width 0.1524)
				(type default)
			)
			(layer "F.SilkS")
		)
		(fp_line
			(start -0.67945 -0.305054)
			(end -0.12065 -0.305054)
			(stroke
				(width 0.1)
				(type default)
			)
			(layer "F.Fab")
		)
		(fp_line
			(start -0.67945 0.3048)
			(end -0.67945 -0.305054)
			(stroke
				(width 0.1)
				(type default)
			)
			(layer "F.Fab")
		)
		(fp_line
			(start -0.12065 -0.305054)
			(end -0.12065 -0.2794)
			(stroke
				(width 0.1)
				(type default)
			)
			(layer "F.Fab")
		)
		(fp_line
			(start -0.12065 -0.2794)
			(end 0.12065 -0.2794)
			(stroke
				(width 0.1)
				(type default)
			)
			(layer "F.Fab")
		)
		(fp_line
			(start -0.12065 0.2794)
			(end -0.12065 0.3048)
			(stroke
				(width 0.1)
				(type default)
			)
			(layer "F.Fab")
		)
		(fp_line
			(start -0.12065 0.3048)
			(end -0.67945 0.3048)
			(stroke
				(width 0.1)
				(type default)
			)
			(layer "F.Fab")
		)
		(fp_line
			(start 0.120396 0.2794)
			(end -0.12065 0.2794)
			(stroke
				(width 0.1)
				(type default)
			)
			(layer "F.Fab")
		)
		(fp_line
			(start 0.120396 0.3048)
			(end 0.120396 0.2794)
			(stroke
				(width 0.1)
				(type default)
			)
			(layer "F.Fab")
		)
		(fp_line
			(start 0.12065 -0.3048)
			(end 0.67945 -0.3048)
			(stroke
				(width 0.1)
				(type default)
			)
			(layer "F.Fab")
		)
		(fp_line
			(start 0.12065 -0.2794)
			(end 0.12065 -0.3048)
			(stroke
				(width 0.1)
				(type default)
			)
			(layer "F.Fab")
		)
		(fp_line
			(start 0.67945 -0.3048)
			(end 0.67945 0.3048)
			(stroke
				(width 0.1)
				(type default)
			)
			(layer "F.Fab")
		)
		(fp_line
			(start 0.67945 0.3048)
			(end 0.120396 0.3048)
			(stroke
				(width 0.1)
				(type default)
			)
			(layer "F.Fab")
		)
		(pad "1" smd circle
			(at -0.40005 0)
			(size 0 0)
			(layers "F.Cu" "F.Mask" "F.Paste")
			(net "SW_P12V_AUX_PVDDCR_CPU1_P0_FLT")
		)
		(pad "2" smd circle
			(at 0.40005 0)
			(size 0 0)
			(layers "F.Cu" "F.Mask" "F.Paste")
			(net "GND")
		)
	)
	(footprint ""
		(layer "F.Cu")
		(at 221.67088 -42.255948)
		(property "Reference" "C1998"
			(at 0 0 0)
			(layer "F.SilkS")
			(hide yes)
			(effects
				(font
					(size 1.27 1.27)
				)
			)
		)
		(property "Value" ""
			(at 0 0 0)
			(layer "F.Fab")
			(effects
				(font
					(size 1.27 1.27)
				)
			)
		)
		(duplicate_pad_numbers_are_jumpers no)
		(fp_line
			(start -0.7874 -0.4064)
			(end 0.7874 -0.4064)
			(stroke
				(width 0.1524)
				(type default)
			)
			(layer "F.SilkS")
		)
		(fp_line
			(start -0.7874 0.4064)
			(end -0.7874 -0.4064)
			(stroke
				(width 0.1524)
				(type default)
			)
			(layer "F.SilkS")
		)
		(fp_line
			(start 0.7874 -0.4064)
			(end 0.7874 0.4064)
			(stroke
				(width 0.1524)
				(type default)
			)
			(layer "F.SilkS")
		)
		(fp_line
			(start 0.7874 0.4064)
			(end -0.7874 0.4064)
			(stroke
				(width 0.1524)
				(type default)
			)
			(layer "F.SilkS")
		)
		(fp_line
			(start -0.67945 -0.305054)
			(end -0.12065 -0.305054)
			(stroke
				(width 0.1)
				(type default)
			)
			(layer "F.Fab")
		)
		(fp_line
			(start -0.67945 0.3048)
			(end -0.67945 -0.305054)
			(stroke
				(width 0.1)
				(type default)
			)
			(layer "F.Fab")
		)
		(fp_line
			(start -0.12065 -0.305054)
			(end -0.12065 -0.2794)
			(stroke
				(width 0.1)
				(type default)
			)
			(layer "F.Fab")
		)
		(fp_line
			(start -0.12065 -0.2794)
			(end 0.12065 -0.2794)
			(stroke
				(width 0.1)
				(type default)
			)
			(layer "F.Fab")
		)
		(fp_line
			(start -0.12065 0.2794)
			(end -0.12065 0.3048)
			(stroke
				(width 0.1)
				(type default)
			)
			(layer "F.Fab")
		)
		(fp_line
			(start -0.12065 0.3048)
			(end -0.67945 0.3048)
			(stroke
				(width 0.1)
				(type default)
			)
			(layer "F.Fab")
		)
		(fp_line
			(start 0.120396 0.2794)
			(end -0.12065 0.2794)
			(stroke
				(width 0.1)
				(type default)
			)
			(layer "F.Fab")
		)
		(fp_line
			(start 0.120396 0.3048)
			(end 0.120396 0.2794)
			(stroke
				(width 0.1)
				(type default)
			)
			(layer "F.Fab")
		)
		(fp_line
			(start 0.12065 -0.3048)
			(end 0.67945 -0.3048)
			(stroke
				(width 0.1)
				(type default)
			)
			(layer "F.Fab")
		)
		(fp_line
			(start 0.12065 -0.2794)
			(end 0.12065 -0.3048)
			(stroke
				(width 0.1)
				(type default)
			)
			(layer "F.Fab")
		)
		(fp_line
			(start 0.67945 -0.3048)
			(end 0.67945 0.3048)
			(stroke
				(width 0.1)
				(type default)
			)
			(layer "F.Fab")
		)
		(fp_line
			(start 0.67945 0.3048)
			(end 0.120396 0.3048)
			(stroke
				(width 0.1)
				(type default)
			)
			(layer "F.Fab")
		)
		(pad "1" smd circle
			(at -0.40005 0)
			(size 0 0)
			(layers "F.Cu" "F.Mask" "F.Paste")
			(net "P3V3_E1S_0")
		)
		(pad "2" smd circle
			(at 0.40005 0)
			(size 0 0)
			(layers "F.Cu" "F.Mask" "F.Paste")
			(net "GND")
		)
	)
)
